# S9S_MB_2U (Grand Teton) — schematic netlist excerpt (pin names and nets, part order shuffled) for the footprints in the layout excerpt that follows; sources: Cadence DE-HDL packaged netlist, KiCad conversion of 03242023_DA0F0TMBIJ0_F0T_Motherboard_J_brd_V01_OCP.brd

R4113  Q_RES  10K 1% CHIP  pkg 0402LF  page 184 : A = PD_PCH_GPP_E_11 ; B = GND
R67  Q_RES  33.2 1% CHIP  pkg 0402LF  page 43 : A = PWRGD_PLT_AUX_CPU0_LVT3_R ; B = PWRGD_PLT_AUX_CPU0_LVT3

(kicad_pcb
	(version 20260206)
	(generator "pcbnew")
	(generator_version "10.0")
	(general
		(thickness 1.6)
		(legacy_teardrops no)
	)
	(paper "A4")
	(title_block
		(title "03242023_DA0F0TMBIJ0_F0T_Motherboard_J_brd_V01_OCP.brd")
		(comment 1 "Grand Teton / footprints 5123-5124 of 6105")
	)
	(layers
		(0 "F.Cu" signal "TOP")
		(4 "In1.Cu" signal "GND")
		(6 "In2.Cu" signal "IN1")
		(8 "In3.Cu" signal "GND1")
		(10 "In4.Cu" signal "IN2")
		(12 "In5.Cu" signal "GND2")
		(14 "In6.Cu" signal "IN3")
		(16 "In7.Cu" signal "GND3")
		(18 "In8.Cu" signal "VCC")
		(20 "In9.Cu" signal "VCC1")
		(22 "In10.Cu" signal "GND4")
		(24 "In11.Cu" signal "IN4")
		(26 "In12.Cu" signal "GND5")
		(28 "In13.Cu" signal "IN5")
		(30 "In14.Cu" signal "GND6")
		(32 "In15.Cu" signal "IN6")
		(34 "In16.Cu" signal "GND7")
		(2 "B.Cu" signal "BOTTOM")
		(9 "F.Adhes" user "F.Adhesive")
		(11 "B.Adhes" user "B.Adhesive")
		(13 "F.Paste" user "Package Geometry/Pastemask Top")
		(15 "B.Paste" user "Package Geometry/Pastemask Bottom")
		(5 "F.SilkS" user "Ref Des/Silkscreen Top")
		(7 "B.SilkS" user "Ref Des/Silkscreen Bottom")
		(1 "F.Mask" user "Board Geometry/Soldermask Top")
		(3 "B.Mask" user "Board Geometry/Soldermask Bottom")
		(17 "Dwgs.User" user "User.Drawings")
		(19 "Cmts.User" user "User.Comments")
		(21 "Eco1.User" user "User.Eco1")
		(23 "Eco2.User" user "User.Eco2")
		(25 "Edge.Cuts" user "Board Geometry/Outline")
		(27 "Margin" user)
		(31 "F.CrtYd" user "Package Geometry/Place Bound Top")
		(29 "B.CrtYd" user "Package Geometry/Place Bound Bottom")
		(35 "F.Fab" user "Ref Des/Assembly Top")
		(33 "B.Fab" user "Ref Des/Assembly Bottom")
	)
	(footprint ""
		(layer "B.Cu")
		(at 369.49888 -45.176948 180)
		(property "Reference" "R4113"
			(at 0 0 0)
			(layer "B.SilkS")
			(hide yes)
			(effects
				(font
					(size 1.27 1.27)
				)
				(justify mirror)
			)
		)
		(property "Value" ""
			(at 0 0 0)
			(layer "B.Fab")
			(effects
				(font
					(size 1.27 1.27)
				)
				(justify mirror)
			)
		)
		(duplicate_pad_numbers_are_jumpers no)
		(fp_line
			(start 0.7874 0.4064)
			(end 0.7874 -0.4064)
			(stroke
				(width 0.1524)
				(type default)
			)
			(layer "B.SilkS")
		)
		(fp_line
			(start 0.7874 -0.4064)
			(end -0.7874 -0.4064)
			(stroke
				(width 0.1524)
				(type default)
			)
			(layer "B.SilkS")
		)
		(fp_line
			(start -0.7874 0.4064)
			(end 0.7874 0.4064)
			(stroke
				(width 0.1524)
				(type default)
			)
			(layer "B.SilkS")
		)
		(fp_line
			(start -0.7874 -0.4064)
			(end -0.7874 0.4064)
			(stroke
				(width 0.1524)
				(type default)
			)
			(layer "B.SilkS")
		)
		(fp_line
			(start 0.67945 0.3048)
			(end 0.67945 -0.305054)
			(stroke
				(width 0.1)
				(type default)
			)
			(layer "B.Fab")
		)
		(fp_line
			(start 0.67945 -0.305054)
			(end 0.12065 -0.305054)
			(stroke
				(width 0.1)
				(type default)
			)
			(layer "B.Fab")
		)
		(fp_line
			(start 0.12065 0.3048)
			(end 0.67945 0.3048)
			(stroke
				(width 0.1)
				(type default)
			)
			(layer "B.Fab")
		)
		(fp_line
			(start 0.12065 0.2794)
			(end 0.12065 0.3048)
			(stroke
				(width 0.1)
				(type default)
			)
			(layer "B.Fab")
		)
		(fp_line
			(start 0.12065 -0.2794)
			(end -0.12065 -0.2794)
			(stroke
				(width 0.1)
				(type default)
			)
			(layer "B.Fab")
		)
		(fp_line
			(start 0.12065 -0.305054)
			(end 0.12065 -0.2794)
			(stroke
				(width 0.1)
				(type default)
			)
			(layer "B.Fab")
		)
		(fp_line
			(start -0.120396 0.3048)
			(end -0.120396 0.2794)
			(stroke
				(width 0.1)
				(type default)
			)
			(layer "B.Fab")
		)
		(fp_line
			(start -0.120396 0.2794)
			(end 0.12065 0.2794)
			(stroke
				(width 0.1)
				(type default)
			)
			(layer "B.Fab")
		)
		(fp_line
			(start -0.12065 -0.2794)
			(end -0.12065 -0.3048)
			(stroke
				(width 0.1)
				(type default)
			)
			(layer "B.Fab")
		)
		(fp_line
			(start -0.12065 -0.3048)
			(end -0.67945 -0.3048)
			(stroke
				(width 0.1)
				(type default)
			)
			(layer "B.Fab")
		)
		(fp_line
			(start -0.67945 0.3048)
			(end -0.120396 0.3048)
			(stroke
				(width 0.1)
				(type default)
			)
			(layer "B.Fab")
		)
		(fp_line
			(start -0.67945 -0.3048)
			(end -0.67945 0.3048)
			(stroke
				(width 0.1)
				(type default)
			)
			(layer "B.Fab")
		)
		(pad "1" smd circle
			(at 0.40005 0)
			(size 0 0)
			(layers "B.Cu" "B.Mask" "B.Paste")
			(net "PD_PCH_GPP_E_11")
		)
		(pad "2" smd circle
			(at -0.40005 0)
			(size 0 0)
			(layers "B.Cu" "B.Mask" "B.Paste")
			(net "GND")
		)
	)
	(footprint ""
		(layer "B.Cu")
		(at 385.46405 -188.70422 -90)
		(property "Reference" "R67"
			(at 0 0 90)
			(layer "B.SilkS")
			(hide yes)
			(effects
				(font
					(size 1.27 1.27)
				)
				(justify mirror)
			)
		)
		(property "Value" ""
			(at 0 0 90)
			(layer "B.Fab")
			(effects
				(font
					(size 1.27 1.27)
				)
				(justify mirror)
			)
		)
		(duplicate_pad_numbers_are_jumpers no)
		(fp_line
			(start -0.7874 0.4064)
			(end 0.7874 0.4064)
			(stroke
				(width 0.1524)
				(type default)
			)
			(layer "B.SilkS")
		)
		(fp_line
			(start 0.7874 0.4064)
			(end 0.7874 -0.4064)
			(stroke
				(width 0.1524)
				(type default)
			)
			(layer "B.SilkS")
		)
		(fp_line
			(start -0.7874 -0.4064)
			(end -0.7874 0.4064)
			(stroke
				(width 0.1524)
				(type default)
			)
			(layer "B.SilkS")
		)
		(fp_line
			(start 0.7874 -0.4064)
			(end -0.7874 -0.4064)
			(stroke
				(width 0.1524)
				(type default)
			)
			(layer "B.SilkS")
		)
		(fp_line
			(start -0.67945 0.3048)
			(end -0.120396 0.3048)
			(stroke
				(width 0.1)
				(type default)
			)
			(layer "B.Fab")
		)
		(fp_line
			(start -0.120396 0.3048)
			(end -0.120396 0.2794)
			(stroke
				(width 0.1)
				(type default)
			)
			(layer "B.Fab")
		)
		(fp_line
			(start 0.12065 0.3048)
			(end 0.67945 0.3048)
			(stroke
				(width 0.1)
				(type default)
			)
			(layer "B.Fab")
		)
		(fp_line
			(start 0.67945 0.3048)
			(end 0.67945 -0.305054)
			(stroke
				(width 0.1)
				(type default)
			)
			(layer "B.Fab")
		)
		(fp_line
			(start -0.120396 0.2794)
			(end 0.12065 0.2794)
			(stroke
				(width 0.1)
				(type default)
			)
			(layer "B.Fab")
		)
		(fp_line
			(start 0.12065 0.2794)
			(end 0.12065 0.3048)
			(stroke
				(width 0.1)
				(type default)
			)
			(layer "B.Fab")
		)
		(fp_line
			(start -0.12065 -0.2794)
			(end -0.12065 -0.3048)
			(stroke
				(width 0.1)
				(type default)
			)
			(layer "B.Fab")
		)
		(fp_line
			(start 0.12065 -0.2794)
			(end -0.12065 -0.2794)
			(stroke
				(width 0.1)
				(type default)
			)
			(layer "B.Fab")
		)
		(fp_line
			(start -0.67945 -0.3048)
			(end -0.67945 0.3048)
			(stroke
				(width 0.1)
				(type default)
			)
			(layer "B.Fab")
		)
		(fp_line
			(start -0.12065 -0.3048)
			(end -0.67945 -0.3048)
			(stroke
				(width 0.1)
				(type default)
			)
			(layer "B.Fab")
		)
		(fp_line
			(start 0.12065 -0.305054)
			(end 0.12065 -0.2794)
			(stroke
				(width 0.1)
				(type default)
			)
			(layer "B.Fab")
		)
		(fp_line
			(start 0.67945 -0.305054)
			(end 0.12065 -0.305054)
			(stroke
				(width 0.1)
				(type default)
			)
			(layer "B.Fab")
		)
		(pad "1" smd circle
			(at 0.40005 0 90)
			(size 0 0)
			(layers "B.Cu" "B.Mask" "B.Paste")
			(net "PWRGD_PLT_AUX_CPU0_LVT3_R")
		)
		(pad "2" smd circle
			(at -0.40005 0 90)
			(size 0 0)
			(layers "B.Cu" "B.Mask" "B.Paste")
			(net "PWRGD_PLT_AUX_CPU0_LVT3")
		)
	)
)
